(kicad_pcb
	(version 20260206)
	(generator "pcbnew")
	(generator_version "10.0")
	(general
		(thickness 1.6)
		(legacy_teardrops no)
	)
	(paper "A4")
	(title_block
		(title "03242023_DA0F0TMBIJ0_F0T_Motherboard_J_brd_V01_OCP.brd")
		(comment 1 "Grand Teton / footprints 5955-5960 of 6105")
	)
	(layers
		(0 "F.Cu" signal "TOP")
		(4 "In1.Cu" signal "GND")
		(6 "In2.Cu" signal "IN1")
		(8 "In3.Cu" signal "GND1")
		(10 "In4.Cu" signal "IN2")
		(12 "In5.Cu" signal "GND2")
		(14 "In6.Cu" signal "IN3")
		(16 "In7.Cu" signal "GND3")
		(18 "In8.Cu" signal "VCC")
		(20 "In9.Cu" signal "VCC1")
		(22 "In10.Cu" signal "GND4")
		(24 "In11.Cu" signal "IN4")
		(26 "In12.Cu" signal "GND5")
		(28 "In13.Cu" signal "IN5")
		(30 "In14.Cu" signal "GND6")
		(32 "In15.Cu" signal "IN6")
		(34 "In16.Cu" signal "GND7")
		(2 "B.Cu" signal "BOTTOM")
		(9 "F.Adhes" user "F.Adhesive")
		(11 "B.Adhes" user "B.Adhesive")
		(13 "F.Paste" user "Package Geometry/Pastemask Top")
		(15 "B.Paste" user "Package Geometry/Pastemask Bottom")
		(5 "F.SilkS" user "Ref Des/Silkscreen Top")
		(7 "B.SilkS" user "Ref Des/Silkscreen Bottom")
		(1 "F.Mask" user "Board Geometry/Soldermask Top")
		(3 "B.Mask" user "Board Geometry/Soldermask Bottom")
		(17 "Dwgs.User" user "User.Drawings")
		(19 "Cmts.User" user "User.Comments")
		(21 "Eco1.User" user "User.Eco1")
		(23 "Eco2.User" user "User.Eco2")
		(25 "Edge.Cuts" user "Board Geometry/Outline")
		(27 "Margin" user)
		(31 "F.CrtYd" user "Package Geometry/Place Bound Top")
		(29 "B.CrtYd" user "Package Geometry/Place Bound Bottom")
		(35 "F.Fab" user "Ref Des/Assembly Top")
		(33 "B.Fab" user "Ref Des/Assembly Bottom")
	)
	(footprint ""
		(layer "B.Cu")
		(at 280.110184 -193.669666 -90)
		(property "Reference" "R1392"
			(at 0 0 90)
			(layer "B.SilkS")
			(hide yes)
			(effects
				(font
					(size 1.27 1.27)
				)
				(justify mirror)
			)
		)
		(property "Value" ""
			(at 0 0 90)
			(layer "B.Fab")
			(effects
				(font
					(size 1.27 1.27)
				)
				(justify mirror)
			)
		)
		(duplicate_pad_numbers_are_jumpers no)
		(fp_line
			(start -0.7874 0.4064)
			(end 0.7874 0.4064)
			(stroke
				(width 0.1524)
				(type default)
			)
			(layer "B.SilkS")
		)
		(fp_line
			(start 0.7874 0.4064)
			(end 0.7874 -0.4064)
			(stroke
				(width 0.1524)
				(type default)
			)
			(layer "B.SilkS")
		)
		(fp_line
			(start -0.7874 -0.4064)
			(end -0.7874 0.4064)
			(stroke
				(width 0.1524)
				(type default)
			)
			(layer "B.SilkS")
		)
		(fp_line
			(start 0.7874 -0.4064)
			(end -0.7874 -0.4064)
			(stroke
				(width 0.1524)
				(type default)
			)
			(layer "B.SilkS")
		)
		(fp_line
			(start -0.67945 0.3048)
			(end -0.120396 0.3048)
			(stroke
				(width 0.1)
				(type default)
			)
			(layer "B.Fab")
		)
		(fp_line
			(start -0.120396 0.3048)
			(end -0.120396 0.2794)
			(stroke
				(width 0.1)
				(type default)
			)
			(layer "B.Fab")
		)
		(fp_line
			(start 0.12065 0.3048)
			(end 0.67945 0.3048)
			(stroke
				(width 0.1)
				(type default)
			)
			(layer "B.Fab")
		)
		(fp_line
			(start 0.67945 0.3048)
			(end 0.67945 -0.305054)
			(stroke
				(width 0.1)
				(type default)
			)
			(layer "B.Fab")
		)
		(fp_line
			(start -0.120396 0.2794)
			(end 0.12065 0.2794)
			(stroke
				(width 0.1)
				(type default)
			)
			(layer "B.Fab")
		)
		(fp_line
			(start 0.12065 0.2794)
			(end 0.12065 0.3048)
			(stroke
				(width 0.1)
				(type default)
			)
			(layer "B.Fab")
		)
		(fp_line
			(start -0.12065 -0.2794)
			(end -0.12065 -0.3048)
			(stroke
				(width 0.1)
				(type default)
			)
			(layer "B.Fab")
		)
		(fp_line
			(start 0.12065 -0.2794)
			(end -0.12065 -0.2794)
			(stroke
				(width 0.1)
				(type default)
			)
			(layer "B.Fab")
		)
		(fp_line
			(start -0.67945 -0.3048)
			(end -0.67945 0.3048)
			(stroke
				(width 0.1)
				(type default)
			)
			(layer "B.Fab")
		)
		(fp_line
			(start -0.12065 -0.3048)
			(end -0.67945 -0.3048)
			(stroke
				(width 0.1)
				(type default)
			)
			(layer "B.Fab")
		)
		(fp_line
			(start 0.12065 -0.305054)
			(end 0.12065 -0.2794)
			(stroke
				(width 0.1)
				(type default)
			)
			(layer "B.Fab")
		)
		(fp_line
			(start 0.67945 -0.305054)
			(end 0.12065 -0.305054)
			(stroke
				(width 0.1)
				(type default)
			)
			(layer "B.Fab")
		)
		(pad "1" smd circle
			(at 0.40005 0 90)
			(size 0 0)
			(layers "B.Cu" "B.Mask" "B.Paste")
			(net "GND")
		)
		(pad "2" smd circle
			(at -0.40005 0 90)
			(size 0 0)
			(layers "B.Cu" "B.Mask" "B.Paste")
			(net "FM_S3M_CPU0_LVC1_GPIO_3")
		)
	)
	(footprint ""
		(layer "B.Cu")
		(at 285.23692 -354.163376 -90)
		(property "Reference" "PC1188_P0_4"
			(at 0 0 90)
			(layer "B.SilkS")
			(hide yes)
			(effects
				(font
					(size 1.27 1.27)
				)
				(justify mirror)
			)
		)
		(property "Value" ""
			(at 0 0 90)
			(layer "B.Fab")
			(effects
				(font
					(size 1.27 1.27)
				)
				(justify mirror)
			)
		)
		(duplicate_pad_numbers_are_jumpers no)
		(fp_line
			(start -1.524 0.762)
			(end 1.524 0.762)
			(stroke
				(width 0.1524)
				(type default)
			)
			(layer "B.SilkS")
		)
		(fp_line
			(start 1.524 0.762)
			(end 1.524 -0.762)
			(stroke
				(width 0.1524)
				(type default)
			)
			(layer "B.SilkS")
		)
		(fp_line
			(start -1.524 -0.762)
			(end -1.524 0.762)
			(stroke
				(width 0.1524)
				(type default)
			)
			(layer "B.SilkS")
		)
		(fp_line
			(start 1.524 -0.762)
			(end -1.524 -0.762)
			(stroke
				(width 0.1524)
				(type default)
			)
			(layer "B.SilkS")
		)
		(fp_line
			(start -1.1049 0.724916)
			(end -1.1049 -0.724916)
			(stroke
				(width 0.1)
				(type default)
			)
			(layer "B.Fab")
		)
		(fp_line
			(start 1.1049 0.724916)
			(end -1.1049 0.724916)
			(stroke
				(width 0.1)
				(type default)
			)
			(layer "B.Fab")
		)
		(fp_line
			(start -1.1049 -0.724916)
			(end 1.1049 -0.724916)
			(stroke
				(width 0.1)
				(type default)
			)
			(layer "B.Fab")
		)
		(fp_line
			(start 1.1049 -0.724916)
			(end 1.1049 0.724916)
			(stroke
				(width 0.1)
				(type default)
			)
			(layer "B.Fab")
		)
		(pad "1" smd rect
			(at 0.889 0 270)
			(size 1.016 1.27)
			(layers "B.Cu" "B.Mask" "B.Paste")
			(net "PVCCFA_EHV_FIVRA_CPU0")
		)
		(pad "2" smd rect
			(at -0.889 0 270)
			(size 1.016 1.27)
			(layers "B.Cu" "B.Mask" "B.Paste")
			(net "GND")
		)
	)
	(footprint ""
		(layer "B.Cu")
		(at 386.58165 -190.82131 90)
		(property "Reference" "R1226"
			(at 0 0 90)
			(layer "B.SilkS")
			(hide yes)
			(effects
				(font
					(size 1.27 1.27)
				)
				(justify mirror)
			)
		)
		(property "Value" ""
			(at 0 0 90)
			(layer "B.Fab")
			(effects
				(font
					(size 1.27 1.27)
				)
				(justify mirror)
			)
		)
		(duplicate_pad_numbers_are_jumpers no)
		(fp_line
			(start 0.7874 -0.4064)
			(end -0.7874 -0.4064)
			(stroke
				(width 0.1524)
				(type default)
			)
			(layer "B.SilkS")
		)
		(fp_line
			(start -0.7874 -0.4064)
			(end -0.7874 0.4064)
			(stroke
				(width 0.1524)
				(type default)
			)
			(layer "B.SilkS")
		)
		(fp_line
			(start 0.7874 0.4064)
			(end 0.7874 -0.4064)
			(stroke
				(width 0.1524)
				(type default)
			)
			(layer "B.SilkS")
		)
		(fp_line
			(start -0.7874 0.4064)
			(end 0.7874 0.4064)
			(stroke
				(width 0.1524)
				(type default)
			)
			(layer "B.SilkS")
		)
		(fp_line
			(start 0.67945 -0.305054)
			(end 0.12065 -0.305054)
			(stroke
				(width 0.1)
				(type default)
			)
			(layer "B.Fab")
		)
		(fp_line
			(start 0.12065 -0.305054)
			(end 0.12065 -0.2794)
			(stroke
				(width 0.1)
				(type default)
			)
			(layer "B.Fab")
		)
		(fp_line
			(start -0.12065 -0.3048)
			(end -0.67945 -0.3048)
			(stroke
				(width 0.1)
				(type default)
			)
			(layer "B.Fab")
		)
		(fp_line
			(start -0.67945 -0.3048)
			(end -0.67945 0.3048)
			(stroke
				(width 0.1)
				(type default)
			)
			(layer "B.Fab")
		)
		(fp_line
			(start 0.12065 -0.2794)
			(end -0.12065 -0.2794)
			(stroke
				(width 0.1)
				(type default)
			)
			(layer "B.Fab")
		)
		(fp_line
			(start -0.12065 -0.2794)
			(end -0.12065 -0.3048)
			(stroke
				(width 0.1)
				(type default)
			)
			(layer "B.Fab")
		)
		(fp_line
			(start 0.12065 0.2794)
			(end 0.12065 0.3048)
			(stroke
				(width 0.1)
				(type default)
			)
			(layer "B.Fab")
		)
		(fp_line
			(start -0.120396 0.2794)
			(end 0.12065 0.2794)
			(stroke
				(width 0.1)
				(type default)
			)
			(layer "B.Fab")
		)
		(fp_line
			(start 0.67945 0.3048)
			(end 0.67945 -0.305054)
			(stroke
				(width 0.1)
				(type default)
			)
			(layer "B.Fab")
		)
		(fp_line
			(start 0.12065 0.3048)
			(end 0.67945 0.3048)
			(stroke
				(width 0.1)
				(type default)
			)
			(layer "B.Fab")
		)
		(fp_line
			(start -0.120396 0.3048)
			(end -0.120396 0.2794)
			(stroke
				(width 0.1)
				(type default)
			)
			(layer "B.Fab")
		)
		(fp_line
			(start -0.67945 0.3048)
			(end -0.120396 0.3048)
			(stroke
				(width 0.1)
				(type default)
			)
			(layer "B.Fab")
		)
		(pad "1" smd circle
			(at 0.40005 0 270)
			(size 0 0)
			(layers "B.Cu" "B.Mask" "B.Paste")
			(net "PD_JTAG_CPU0_PLD_TCK")
		)
		(pad "2" smd circle
			(at -0.40005 0 270)
			(size 0 0)
			(layers "B.Cu" "B.Mask" "B.Paste")
			(net "GND")
		)
	)
	(footprint ""
		(layer "B.Cu")
		(at 348.479364 -356.192836 180)
		(property "Reference" "C3271"
			(at 0 0 0)
			(layer "B.SilkS")
			(hide yes)
			(effects
				(font
					(size 1.27 1.27)
				)
				(justify mirror)
			)
		)
		(property "Value" ""
			(at 0 0 0)
			(layer "B.Fab")
			(effects
				(font
					(size 1.27 1.27)
				)
				(justify mirror)
			)
		)
		(duplicate_pad_numbers_are_jumpers no)
		(fp_line
			(start 0.7874 0.4064)
			(end 0.7874 -0.4064)
			(stroke
				(width 0.1524)
				(type default)
			)
			(layer "B.SilkS")
		)
		(fp_line
			(start 0.7874 -0.4064)
			(end -0.7874 -0.4064)
			(stroke
				(width 0.1524)
				(type default)
			)
			(layer "B.SilkS")
		)
		(fp_line
			(start -0.7874 0.4064)
			(end 0.7874 0.4064)
			(stroke
				(width 0.1524)
				(type default)
			)
			(layer "B.SilkS")
		)
		(fp_line
			(start -0.7874 -0.4064)
			(end -0.7874 0.4064)
			(stroke
				(width 0.1524)
				(type default)
			)
			(layer "B.SilkS")
		)
		(fp_line
			(start 0.67945 0.3048)
			(end 0.67945 -0.305054)
			(stroke
				(width 0.1)
				(type default)
			)
			(layer "B.Fab")
		)
		(fp_line
			(start 0.67945 -0.305054)
			(end 0.12065 -0.305054)
			(stroke
				(width 0.1)
				(type default)
			)
			(layer "B.Fab")
		)
		(fp_line
			(start 0.12065 0.3048)
			(end 0.67945 0.3048)
			(stroke
				(width 0.1)
				(type default)
			)
			(layer "B.Fab")
		)
		(fp_line
			(start 0.12065 0.2794)
			(end 0.12065 0.3048)
			(stroke
				(width 0.1)
				(type default)
			)
			(layer "B.Fab")
		)
		(fp_line
			(start 0.12065 -0.2794)
			(end -0.12065 -0.2794)
			(stroke
				(width 0.1)
				(type default)
			)
			(layer "B.Fab")
		)
		(fp_line
			(start 0.12065 -0.305054)
			(end 0.12065 -0.2794)
			(stroke
				(width 0.1)
				(type default)
			)
			(layer "B.Fab")
		)
		(fp_line
			(start -0.120396 0.3048)
			(end -0.120396 0.2794)
			(stroke
				(width 0.1)
				(type default)
			)
			(layer "B.Fab")
		)
		(fp_line
			(start -0.120396 0.2794)
			(end 0.12065 0.2794)
			(stroke
				(width 0.1)
				(type default)
			)
			(layer "B.Fab")
		)
		(fp_line
			(start -0.12065 -0.2794)
			(end -0.12065 -0.3048)
			(stroke
				(width 0.1)
				(type default)
			)
			(layer "B.Fab")
		)
		(fp_line
			(start -0.12065 -0.3048)
			(end -0.67945 -0.3048)
			(stroke
				(width 0.1)
				(type default)
			)
			(layer "B.Fab")
		)
		(fp_line
			(start -0.67945 0.3048)
			(end -0.120396 0.3048)
			(stroke
				(width 0.1)
				(type default)
			)
			(layer "B.Fab")
		)
		(fp_line
			(start -0.67945 -0.3048)
			(end -0.67945 0.3048)
			(stroke
				(width 0.1)
				(type default)
			)
			(layer "B.Fab")
		)
		(pad "1" smd circle
			(at 0.40005 0)
			(size 0 0)
			(layers "B.Cu" "B.Mask" "B.Paste")
			(net "PVNN_TERM_CPU0")
		)
		(pad "2" smd circle
			(at -0.40005 0)
			(size 0 0)
			(layers "B.Cu" "B.Mask" "B.Paste")
			(net "GND")
		)
	)
	(footprint ""
		(layer "B.Cu")
		(at 301.724314 -353.955096 -90)
		(property "Reference" "PC613_P0_2"
			(at 0 0 90)
			(layer "B.SilkS")
			(hide yes)
			(effects
				(font
					(size 1.27 1.27)
				)
				(justify mirror)
			)
		)
		(property "Value" ""
			(at 0 0 90)
			(layer "B.Fab")
			(effects
				(font
					(size 1.27 1.27)
				)
				(justify mirror)
			)
		)
		(duplicate_pad_numbers_are_jumpers no)
		(fp_line
			(start -0.7874 0.4064)
			(end 0.7874 0.4064)
			(stroke
				(width 0.1524)
				(type default)
			)
			(layer "B.SilkS")
		)
		(fp_line
			(start 0.7874 0.4064)
			(end 0.7874 -0.4064)
			(stroke
				(width 0.1524)
				(type default)
			)
			(layer "B.SilkS")
		)
		(fp_line
			(start -0.7874 -0.4064)
			(end -0.7874 0.4064)
			(stroke
				(width 0.1524)
				(type default)
			)
			(layer "B.SilkS")
		)
		(fp_line
			(start 0.7874 -0.4064)
			(end -0.7874 -0.4064)
			(stroke
				(width 0.1524)
				(type default)
			)
			(layer "B.SilkS")
		)
		(fp_line
			(start -0.67945 0.3048)
			(end -0.120396 0.3048)
			(stroke
				(width 0.1)
				(type default)
			)
			(layer "B.Fab")
		)
		(fp_line
			(start -0.120396 0.3048)
			(end -0.120396 0.2794)
			(stroke
				(width 0.1)
				(type default)
			)
			(layer "B.Fab")
		)
		(fp_line
			(start 0.12065 0.3048)
			(end 0.67945 0.3048)
			(stroke
				(width 0.1)
				(type default)
			)
			(layer "B.Fab")
		)
		(fp_line
			(start 0.67945 0.3048)
			(end 0.67945 -0.305054)
			(stroke
				(width 0.1)
				(type default)
			)
			(layer "B.Fab")
		)
		(fp_line
			(start -0.120396 0.2794)
			(end 0.12065 0.2794)
			(stroke
				(width 0.1)
				(type default)
			)
			(layer "B.Fab")
		)
		(fp_line
			(start 0.12065 0.2794)
			(end 0.12065 0.3048)
			(stroke
				(width 0.1)
				(type default)
			)
			(layer "B.Fab")
		)
		(fp_line
			(start -0.12065 -0.2794)
			(end -0.12065 -0.3048)
			(stroke
				(width 0.1)
				(type default)
			)
			(layer "B.Fab")
		)
		(fp_line
			(start 0.12065 -0.2794)
			(end -0.12065 -0.2794)
			(stroke
				(width 0.1)
				(type default)
			)
			(layer "B.Fab")
		)
		(fp_line
			(start -0.67945 -0.3048)
			(end -0.67945 0.3048)
			(stroke
				(width 0.1)
				(type default)
			)
			(layer "B.Fab")
		)
		(fp_line
			(start -0.12065 -0.3048)
			(end -0.67945 -0.3048)
			(stroke
				(width 0.1)
				(type default)
			)
			(layer "B.Fab")
		)
		(fp_line
			(start 0.12065 -0.305054)
			(end 0.12065 -0.2794)
			(stroke
				(width 0.1)
				(type default)
			)
			(layer "B.Fab")
		)
		(fp_line
			(start 0.67945 -0.305054)
			(end 0.12065 -0.305054)
			(stroke
				(width 0.1)
				(type default)
			)
			(layer "B.Fab")
		)
		(pad "1" smd circle
			(at 0.40005 0 90)
			(size 0 0)
			(layers "B.Cu" "B.Mask" "B.Paste")
			(net "PVCCFA_EHV_FIVRA_CPU0")
		)
		(pad "2" smd circle
			(at -0.40005 0 90)
			(size 0 0)
			(layers "B.Cu" "B.Mask" "B.Paste")
			(net "GND")
		)
	)
	(footprint ""
		(layer "B.Cu")
		(at 190.248286 -193.615056 -90)
		(property "Reference" "R815"
			(at 0 0 90)
			(layer "B.SilkS")
			(hide yes)
			(effects
				(font
					(size 1.27 1.27)
				)
				(justify mirror)
			)
		)
		(property "Value" ""
			(at 0 0 90)
			(layer "B.Fab")
			(effects
				(font
					(size 1.27 1.27)
				)
				(justify mirror)
			)
		)
		(duplicate_pad_numbers_are_jumpers no)
		(fp_line
			(start -0.7874 0.4064)
			(end 0.7874 0.4064)
			(stroke
				(width 0.1524)
				(type default)
			)
			(layer "B.SilkS")
		)
		(fp_line
			(start 0.7874 0.4064)
			(end 0.7874 -0.4064)
			(stroke
				(width 0.1524)
				(type default)
			)
			(layer "B.SilkS")
		)
		(fp_line
			(start -0.7874 -0.4064)
			(end -0.7874 0.4064)
			(stroke
				(width 0.1524)
				(type default)
			)
			(layer "B.SilkS")
		)
		(fp_line
			(start 0.7874 -0.4064)
			(end -0.7874 -0.4064)
			(stroke
				(width 0.1524)
				(type default)
			)
			(layer "B.SilkS")
		)
		(fp_line
			(start -0.67945 0.3048)
			(end -0.120396 0.3048)
			(stroke
				(width 0.1)
				(type default)
			)
			(layer "B.Fab")
		)
		(fp_line
			(start -0.120396 0.3048)
			(end -0.120396 0.2794)
			(stroke
				(width 0.1)
				(type default)
			)
			(layer "B.Fab")
		)
		(fp_line
			(start 0.12065 0.3048)
			(end 0.67945 0.3048)
			(stroke
				(width 0.1)
				(type default)
			)
			(layer "B.Fab")
		)
		(fp_line
			(start 0.67945 0.3048)
			(end 0.67945 -0.305054)
			(stroke
				(width 0.1)
				(type default)
			)
			(layer "B.Fab")
		)
		(fp_line
			(start -0.120396 0.2794)
			(end 0.12065 0.2794)
			(stroke
				(width 0.1)
				(type default)
			)
			(layer "B.Fab")
		)
		(fp_line
			(start 0.12065 0.2794)
			(end 0.12065 0.3048)
			(stroke
				(width 0.1)
				(type default)
			)
			(layer "B.Fab")
		)
		(fp_line
			(start -0.12065 -0.2794)
			(end -0.12065 -0.3048)
			(stroke
				(width 0.1)
				(type default)
			)
			(layer "B.Fab")
		)
		(fp_line
			(start 0.12065 -0.2794)
			(end -0.12065 -0.2794)
			(stroke
				(width 0.1)
				(type default)
			)
			(layer "B.Fab")
		)
		(fp_line
			(start -0.67945 -0.3048)
			(end -0.67945 0.3048)
			(stroke
				(width 0.1)
				(type default)
			)
			(layer "B.Fab")
		)
		(fp_line
			(start -0.12065 -0.3048)
			(end -0.67945 -0.3048)
			(stroke
				(width 0.1)
				(type default)
			)
			(layer "B.Fab")
		)
		(fp_line
			(start 0.12065 -0.305054)
			(end 0.12065 -0.2794)
			(stroke
				(width 0.1)
				(type default)
			)
			(layer "B.Fab")
		)
		(fp_line
			(start 0.67945 -0.305054)
			(end 0.12065 -0.305054)
			(stroke
				(width 0.1)
				(type default)
			)
			(layer "B.Fab")
		)
		(pad "1" smd circle
			(at 0.40005 0 90)
			(size 0 0)
			(layers "B.Cu" "B.Mask" "B.Paste")
			(net "RST_PLD_CPU1_DRAM_GH_N")
		)
		(pad "2" smd circle
			(at -0.40005 0 90)
			(size 0 0)
			(layers "B.Cu" "B.Mask" "B.Paste")
			(net "RST_M_GH_CPU1_FPGA_N")
		)
	)
)
